(kicad_pcb
	(version 20260206)
	(generator "pcbnew")
	(generator_version "10.0")
	(general
		(thickness 1.6)
		(legacy_teardrops no)
	)
	(paper "A4")
	(title_block
		(title "Bryce Canyon_IOM_IOC_16318-2_OCP.brd")
		(comment 1 "Bryce Canyon / footprints 1233-1239 of 1605")
	)
	(layers
		(0 "F.Cu" signal "TOP")
		(4 "In1.Cu" signal "L2GND")
		(6 "In2.Cu" signal "L3")
		(8 "In3.Cu" signal "L4VCC")
		(10 "In4.Cu" signal "L5VCC")
		(12 "In5.Cu" signal "L6")
		(14 "In6.Cu" signal "L7GND")
		(2 "B.Cu" signal "BOTTOM")
		(9 "F.Adhes" user "F.Adhesive")
		(11 "B.Adhes" user "B.Adhesive")
		(13 "F.Paste" user "Package Geometry/Pastemask Top")
		(15 "B.Paste" user "Package Geometry/Pastemask Bottom")
		(5 "F.SilkS" user "Ref Des/Silkscreen Top")
		(7 "B.SilkS" user "Ref Des/Silkscreen Bottom")
		(1 "F.Mask" user "Board Geometry/Soldermask Top")
		(3 "B.Mask" user "Board Geometry/Soldermask Bottom")
		(17 "Dwgs.User" user "User.Drawings")
		(19 "Cmts.User" user "User.Comments")
		(21 "Eco1.User" user "User.Eco1")
		(23 "Eco2.User" user "User.Eco2")
		(25 "Edge.Cuts" user "Board Geometry/Outline")
		(27 "Margin" user)
		(31 "F.CrtYd" user "Package Geometry/Place Bound Top")
		(29 "B.CrtYd" user "Package Geometry/Place Bound Bottom")
		(35 "F.Fab" user "Ref Des/Assembly Top")
		(33 "B.Fab" user "Ref Des/Assembly Bottom")
	)
	(footprint ""
		(layer "B.Cu")
		(at 56.983884 -158.44393 180)
		(property "Reference" "C96"
			(at 0 0 0)
			(layer "B.SilkS")
			(hide yes)
			(effects
				(font
					(size 1.27 1.27)
				)
				(justify mirror)
			)
		)
		(property "Value" "SC100P50V2JN-3GP"
			(at -1.1811 -2.7051 180)
			(unlocked yes)
			(layer "B.Fab")
			(hide yes)
			(effects
				(font
					(size 1.016 1.016)
					(thickness 0.1524)
				)
				(justify mirror)
			)
		)
		(property "Device Type" "C402H22"
			(at -1.1811 -4.2291 180)
			(unlocked yes)
			(layer "B.Fab")
			(hide yes)
			(effects
				(font
					(size 1.016 1.016)
					(thickness 0.1524)
				)
				(justify mirror)
			)
		)
		(duplicate_pad_numbers_are_jumpers no)
		(fp_rect
			(start 0.4318 0.9525)
			(end -0.4318 -0.9525)
			(stroke
				(width 0)
				(type default)
			)
			(fill no)
			(layer "B.CrtYd")
		)
		(fp_rect
			(start 0.4318 0.9525)
			(end -0.4318 -0.9525)
			(stroke
				(width 0)
				(type default)
			)
			(fill no)
			(layer "B.Fab")
		)
		(pad "1" smd custom
			(at 0 -0.4445)
			(size 0.1524 0.1524)
			(layers "B.Cu" "B.Mask" "B.Paste")
			(net "VPLLAV33")
			(options
				(clearance outline)
				(anchor circle)
			)
			(primitives
				(gr_poly
					(pts
						(arc
							(start 0.3048 0.2032)
							(mid 0.275042 0.275042)
							(end 0.2032 0.3048)
						)
						(arc
							(start -0.2032 0.3048)
							(mid -0.275042 0.275042)
							(end -0.3048 0.2032)
						)
						(arc
							(start -0.3048 -0.2032)
							(mid -0.275042 -0.275042)
							(end -0.2032 -0.3048)
						)
						(arc
							(start 0.2032 -0.3048)
							(mid 0.275042 -0.275042)
							(end 0.3048 -0.2032)
						)
					)
					(width 0)
					(fill yes)
				)
			)
		)
		(pad "2" smd custom
			(at 0 0.4445)
			(size 0.1524 0.1524)
			(layers "B.Cu" "B.Mask" "B.Paste")
			(net "GND")
			(options
				(clearance outline)
				(anchor circle)
			)
			(primitives
				(gr_poly
					(pts
						(arc
							(start 0.3048 0.2032)
							(mid 0.275042 0.275042)
							(end 0.2032 0.3048)
						)
						(arc
							(start -0.2032 0.3048)
							(mid -0.275042 0.275042)
							(end -0.3048 0.2032)
						)
						(arc
							(start -0.3048 -0.2032)
							(mid -0.275042 -0.275042)
							(end -0.2032 -0.3048)
						)
						(arc
							(start 0.2032 -0.3048)
							(mid 0.275042 -0.275042)
							(end 0.3048 -0.2032)
						)
					)
					(width 0)
					(fill yes)
				)
			)
		)
	)
	(footprint ""
		(layer "B.Cu")
		(at 164.465 -51.2064)
		(property "Reference" "C329"
			(at 0 0 0)
			(layer "B.SilkS")
			(hide yes)
			(effects
				(font
					(size 1.27 1.27)
				)
				(justify mirror)
			)
		)
		(property "Value" "SCD1U16V2KX-3GP"
			(at -1.1811 -2.7051 0)
			(unlocked yes)
			(layer "B.Fab")
			(hide yes)
			(effects
				(font
					(size 1.016 1.016)
					(thickness 0.1524)
				)
				(justify mirror)
			)
		)
		(property "Device Type" "C402H22"
			(at -1.1811 -4.2291 0)
			(unlocked yes)
			(layer "B.Fab")
			(hide yes)
			(effects
				(font
					(size 1.016 1.016)
					(thickness 0.1524)
				)
				(justify mirror)
			)
		)
		(duplicate_pad_numbers_are_jumpers no)
		(fp_rect
			(start 0.4318 0.9525)
			(end -0.4318 -0.9525)
			(stroke
				(width 0)
				(type default)
			)
			(fill no)
			(layer "B.CrtYd")
		)
		(fp_rect
			(start 0.4318 0.9525)
			(end -0.4318 -0.9525)
			(stroke
				(width 0)
				(type default)
			)
			(fill no)
			(layer "B.Fab")
		)
		(pad "1" smd custom
			(at 0 -0.4445 180)
			(size 0.1524 0.1524)
			(layers "B.Cu" "B.Mask" "B.Paste")
			(net "P3V3_STBY")
			(options
				(clearance outline)
				(anchor circle)
			)
			(primitives
				(gr_poly
					(pts
						(arc
							(start 0.3048 0.2032)
							(mid 0.275042 0.275042)
							(end 0.2032 0.3048)
						)
						(arc
							(start -0.2032 0.3048)
							(mid -0.275042 0.275042)
							(end -0.3048 0.2032)
						)
						(arc
							(start -0.3048 -0.2032)
							(mid -0.275042 -0.275042)
							(end -0.2032 -0.3048)
						)
						(arc
							(start 0.2032 -0.3048)
							(mid 0.275042 -0.275042)
							(end 0.3048 -0.2032)
						)
					)
					(width 0)
					(fill yes)
				)
			)
		)
		(pad "2" smd custom
			(at 0 0.4445 180)
			(size 0.1524 0.1524)
			(layers "B.Cu" "B.Mask" "B.Paste")
			(net "GND")
			(options
				(clearance outline)
				(anchor circle)
			)
			(primitives
				(gr_poly
					(pts
						(arc
							(start 0.3048 0.2032)
							(mid 0.275042 0.275042)
							(end 0.2032 0.3048)
						)
						(arc
							(start -0.2032 0.3048)
							(mid -0.275042 0.275042)
							(end -0.3048 0.2032)
						)
						(arc
							(start -0.3048 -0.2032)
							(mid -0.275042 -0.275042)
							(end -0.2032 -0.3048)
						)
						(arc
							(start 0.2032 -0.3048)
							(mid 0.275042 -0.275042)
							(end 0.3048 -0.2032)
						)
					)
					(width 0)
					(fill yes)
				)
			)
		)
	)
	(footprint ""
		(layer "B.Cu")
		(at 57.1246 -150.6728 -90)
		(property "Reference" "R388"
			(at 0 0 90)
			(layer "B.SilkS")
			(hide yes)
			(effects
				(font
					(size 1.27 1.27)
				)
				(justify mirror)
			)
		)
		(property "Value" "4K7R2F-GP"
			(at -0.064008 -3.993896 270)
			(unlocked yes)
			(layer "B.Fab")
			(hide yes)
			(effects
				(font
					(size 1.016 1.016)
					(thickness 0.1524)
				)
				(justify mirror)
			)
		)
		(property "Device Type" "R402H16"
			(at -0.064008 -5.517896 270)
			(unlocked yes)
			(layer "B.Fab")
			(hide yes)
			(effects
				(font
					(size 1.016 1.016)
					(thickness 0.1524)
				)
				(justify mirror)
			)
		)
		(duplicate_pad_numbers_are_jumpers no)
		(fp_line
			(start -0.508 -0.9398)
			(end 0.508 -0.9398)
			(stroke
				(width 0.1524)
				(type default)
			)
			(layer "B.SilkS")
		)
		(fp_line
			(start 0.508 -0.9398)
			(end 0.508 0.9398)
			(stroke
				(width 0.1524)
				(type default)
			)
			(layer "B.SilkS")
		)
		(fp_rect
			(start 0.508 0.9398)
			(end -0.508 -0.9398)
			(stroke
				(width 0)
				(type default)
			)
			(fill no)
			(layer "B.CrtYd")
		)
		(fp_rect
			(start 0.508 0.9398)
			(end -0.508 -0.9398)
			(stroke
				(width 0)
				(type default)
			)
			(fill no)
			(layer "B.Fab")
		)
		(pad "1" smd custom
			(at 0 -0.4445 90)
			(size 0.1397 0.1397)
			(layers "B.Cu" "B.Mask" "B.Paste")
			(net "GND")
			(options
				(clearance outline)
				(anchor circle)
			)
			(primitives
				(gr_poly
					(pts
						(arc
							(start -0.1778 0.2794)
							(mid -0.249642 0.249642)
							(end -0.2794 0.1778)
						)
						(arc
							(start -0.2794 -0.1778)
							(mid -0.249642 -0.249642)
							(end -0.1778 -0.2794)
						)
						(arc
							(start 0.1778 -0.2794)
							(mid 0.249642 -0.249642)
							(end 0.2794 -0.1778)
						)
						(arc
							(start 0.2794 0.1778)
							(mid 0.249642 0.249642)
							(end 0.1778 0.2794)
						)
					)
					(width 0)
					(fill yes)
				)
			)
		)
		(pad "2" smd custom
			(at 0 0.4445 90)
			(size 0.1397 0.1397)
			(layers "B.Cu" "B.Mask" "B.Paste")
			(net "MAC1_TXD2")
			(options
				(clearance outline)
				(anchor circle)
			)
			(primitives
				(gr_poly
					(pts
						(arc
							(start -0.1778 0.2794)
							(mid -0.249642 0.249642)
							(end -0.2794 0.1778)
						)
						(arc
							(start -0.2794 -0.1778)
							(mid -0.249642 -0.249642)
							(end -0.1778 -0.2794)
						)
						(arc
							(start 0.1778 -0.2794)
							(mid 0.249642 -0.249642)
							(end 0.2794 -0.1778)
						)
						(arc
							(start 0.2794 0.1778)
							(mid 0.249642 0.249642)
							(end 0.1778 0.2794)
						)
					)
					(width 0)
					(fill yes)
				)
			)
		)
	)
	(footprint ""
		(layer "B.Cu")
		(at 24.8666 -129.1082 180)
		(property "Reference" "R244"
			(at 0 0 0)
			(layer "B.SilkS")
			(hide yes)
			(effects
				(font
					(size 1.27 1.27)
				)
				(justify mirror)
			)
		)
		(property "Value" "120R2F-GP"
			(at -0.064008 -3.993896 180)
			(unlocked yes)
			(layer "B.Fab")
			(hide yes)
			(effects
				(font
					(size 1.016 1.016)
					(thickness 0.1524)
				)
				(justify mirror)
			)
		)
		(property "Device Type" "R402H16"
			(at -0.064008 -5.517896 180)
			(unlocked yes)
			(layer "B.Fab")
			(hide yes)
			(effects
				(font
					(size 1.016 1.016)
					(thickness 0.1524)
				)
				(justify mirror)
			)
		)
		(duplicate_pad_numbers_are_jumpers no)
		(fp_line
			(start 0.508 -0.9398)
			(end 0.508 0.9398)
			(stroke
				(width 0.1524)
				(type default)
			)
			(layer "B.SilkS")
		)
		(fp_line
			(start -0.508 -0.9398)
			(end 0.508 -0.9398)
			(stroke
				(width 0.1524)
				(type default)
			)
			(layer "B.SilkS")
		)
		(fp_rect
			(start 0.508 0.9398)
			(end -0.508 -0.9398)
			(stroke
				(width 0)
				(type default)
			)
			(fill no)
			(layer "B.CrtYd")
		)
		(fp_rect
			(start 0.508 0.9398)
			(end -0.508 -0.9398)
			(stroke
				(width 0)
				(type default)
			)
			(fill no)
			(layer "B.Fab")
		)
		(pad "1" smd custom
			(at 0 -0.4445)
			(size 0.1397 0.1397)
			(layers "B.Cu" "B.Mask" "B.Paste")
			(net "GND")
			(options
				(clearance outline)
				(anchor circle)
			)
			(primitives
				(gr_poly
					(pts
						(arc
							(start -0.1778 0.2794)
							(mid -0.249642 0.249642)
							(end -0.2794 0.1778)
						)
						(arc
							(start -0.2794 -0.1778)
							(mid -0.249642 -0.249642)
							(end -0.1778 -0.2794)
						)
						(arc
							(start 0.1778 -0.2794)
							(mid 0.249642 -0.249642)
							(end 0.2794 -0.1778)
						)
						(arc
							(start 0.2794 0.1778)
							(mid 0.249642 0.249642)
							(end 0.1778 0.2794)
						)
					)
					(width 0)
					(fill yes)
				)
			)
		)
		(pad "2" smd custom
			(at 0 0.4445)
			(size 0.1397 0.1397)
			(layers "B.Cu" "B.Mask" "B.Paste")
			(net "MEMA_5")
			(options
				(clearance outline)
				(anchor circle)
			)
			(primitives
				(gr_poly
					(pts
						(arc
							(start -0.1778 0.2794)
							(mid -0.249642 0.249642)
							(end -0.2794 0.1778)
						)
						(arc
							(start -0.2794 -0.1778)
							(mid -0.249642 -0.249642)
							(end -0.1778 -0.2794)
						)
						(arc
							(start 0.1778 -0.2794)
							(mid 0.249642 -0.249642)
							(end 0.2794 -0.1778)
						)
						(arc
							(start 0.2794 0.1778)
							(mid 0.249642 0.249642)
							(end 0.1778 0.2794)
						)
					)
					(width 0)
					(fill yes)
				)
			)
		)
	)
	(footprint ""
		(layer "B.Cu")
		(at 186.51728 -73.1901 90)
		(property "Reference" "C451"
			(at 0 0 90)
			(layer "B.SilkS")
			(hide yes)
			(effects
				(font
					(size 1.27 1.27)
				)
				(justify mirror)
			)
		)
		(property "Value" "SCD1U16V2KX-3GP"
			(at -1.1811 -2.7051 90)
			(unlocked yes)
			(layer "B.Fab")
			(hide yes)
			(effects
				(font
					(size 1.016 1.016)
					(thickness 0.1524)
				)
				(justify mirror)
			)
		)
		(property "Device Type" "C402H22"
			(at -1.1811 -4.2291 90)
			(unlocked yes)
			(layer "B.Fab")
			(hide yes)
			(effects
				(font
					(size 1.016 1.016)
					(thickness 0.1524)
				)
				(justify mirror)
			)
		)
		(duplicate_pad_numbers_are_jumpers no)
		(fp_rect
			(start 0.4318 0.9525)
			(end -0.4318 -0.9525)
			(stroke
				(width 0)
				(type default)
			)
			(fill no)
			(layer "B.CrtYd")
		)
		(fp_rect
			(start 0.4318 0.9525)
			(end -0.4318 -0.9525)
			(stroke
				(width 0)
				(type default)
			)
			(fill no)
			(layer "B.Fab")
		)
		(pad "1" smd custom
			(at 0 -0.4445 270)
			(size 0.1524 0.1524)
			(layers "B.Cu" "B.Mask" "B.Paste")
			(net "P1V8")
			(options
				(clearance outline)
				(anchor circle)
			)
			(primitives
				(gr_poly
					(pts
						(arc
							(start 0.3048 0.2032)
							(mid 0.275042 0.275042)
							(end 0.2032 0.3048)
						)
						(arc
							(start -0.2032 0.3048)
							(mid -0.275042 0.275042)
							(end -0.3048 0.2032)
						)
						(arc
							(start -0.3048 -0.2032)
							(mid -0.275042 -0.275042)
							(end -0.2032 -0.3048)
						)
						(arc
							(start 0.2032 -0.3048)
							(mid 0.275042 -0.275042)
							(end 0.3048 -0.2032)
						)
					)
					(width 0)
					(fill yes)
				)
			)
		)
		(pad "2" smd custom
			(at 0 0.4445 270)
			(size 0.1524 0.1524)
			(layers "B.Cu" "B.Mask" "B.Paste")
			(net "GND")
			(options
				(clearance outline)
				(anchor circle)
			)
			(primitives
				(gr_poly
					(pts
						(arc
							(start 0.3048 0.2032)
							(mid 0.275042 0.275042)
							(end 0.2032 0.3048)
						)
						(arc
							(start -0.2032 0.3048)
							(mid -0.275042 0.275042)
							(end -0.3048 0.2032)
						)
						(arc
							(start -0.3048 -0.2032)
							(mid -0.275042 -0.275042)
							(end -0.2032 -0.3048)
						)
						(arc
							(start 0.2032 -0.3048)
							(mid 0.275042 -0.275042)
							(end 0.3048 -0.2032)
						)
					)
					(width 0)
					(fill yes)
				)
			)
		)
	)
	(footprint ""
		(layer "B.Cu")
		(at 185.98642 -78.630526)
		(property "Reference" "R620"
			(at 0 0 0)
			(layer "B.SilkS")
			(hide yes)
			(effects
				(font
					(size 1.27 1.27)
				)
				(justify mirror)
			)
		)
		(property "Value" "4K7R2F-GP"
			(at -0.064008 -3.993896 0)
			(unlocked yes)
			(layer "B.Fab")
			(hide yes)
			(effects
				(font
					(size 1.016 1.016)
					(thickness 0.1524)
				)
				(justify mirror)
			)
		)
		(property "Device Type" "R402H16"
			(at -0.064008 -5.517896 0)
			(unlocked yes)
			(layer "B.Fab")
			(hide yes)
			(effects
				(font
					(size 1.016 1.016)
					(thickness 0.1524)
				)
				(justify mirror)
			)
		)
		(duplicate_pad_numbers_are_jumpers no)
		(fp_line
			(start -0.508 -0.9398)
			(end 0.508 -0.9398)
			(stroke
				(width 0.1524)
				(type default)
			)
			(layer "B.SilkS")
		)
		(fp_line
			(start 0.508 -0.9398)
			(end 0.508 0.9398)
			(stroke
				(width 0.1524)
				(type default)
			)
			(layer "B.SilkS")
		)
		(fp_rect
			(start 0.508 0.9398)
			(end -0.508 -0.9398)
			(stroke
				(width 0)
				(type default)
			)
			(fill no)
			(layer "B.CrtYd")
		)
		(fp_rect
			(start 0.508 0.9398)
			(end -0.508 -0.9398)
			(stroke
				(width 0)
				(type default)
			)
			(fill no)
			(layer "B.Fab")
		)
		(pad "1" smd custom
			(at 0 -0.4445 180)
			(size 0.1397 0.1397)
			(layers "B.Cu" "B.Mask" "B.Paste")
			(net "P1V8")
			(options
				(clearance outline)
				(anchor circle)
			)
			(primitives
				(gr_poly
					(pts
						(arc
							(start -0.1778 0.2794)
							(mid -0.249642 0.249642)
							(end -0.2794 0.1778)
						)
						(arc
							(start -0.2794 -0.1778)
							(mid -0.249642 -0.249642)
							(end -0.1778 -0.2794)
						)
						(arc
							(start 0.1778 -0.2794)
							(mid 0.249642 -0.249642)
							(end 0.2794 -0.1778)
						)
						(arc
							(start 0.2794 0.1778)
							(mid 0.249642 0.249642)
							(end 0.1778 0.2794)
						)
					)
					(width 0)
					(fill yes)
				)
			)
		)
		(pad "2" smd custom
			(at 0 0.4445 180)
			(size 0.1397 0.1397)
			(layers "B.Cu" "B.Mask" "B.Paste")
			(net "IOC_UART_1_RX")
			(options
				(clearance outline)
				(anchor circle)
			)
			(primitives
				(gr_poly
					(pts
						(arc
							(start -0.1778 0.2794)
							(mid -0.249642 0.249642)
							(end -0.2794 0.1778)
						)
						(arc
							(start -0.2794 -0.1778)
							(mid -0.249642 -0.249642)
							(end -0.1778 -0.2794)
						)
						(arc
							(start 0.1778 -0.2794)
							(mid 0.249642 -0.249642)
							(end 0.2794 -0.1778)
						)
						(arc
							(start 0.2794 0.1778)
							(mid 0.249642 0.249642)
							(end 0.1778 0.2794)
						)
					)
					(width 0)
					(fill yes)
				)
			)
		)
	)
	(footprint ""
		(layer "B.Cu")
		(at 36.9316 -135.7122 180)
		(property "Reference" "R277"
			(at 0 0 0)
			(layer "B.SilkS")
			(hide yes)
			(effects
				(font
					(size 1.27 1.27)
				)
				(justify mirror)
			)
		)
		(property "Value" "33R2F-3-GP"
			(at -0.064008 -3.993896 180)
			(unlocked yes)
			(layer "B.Fab")
			(hide yes)
			(effects
				(font
					(size 1.016 1.016)
					(thickness 0.1524)
				)
				(justify mirror)
			)
		)
		(property "Device Type" "R402H16"
			(at -0.064008 -5.517896 180)
			(unlocked yes)
			(layer "B.Fab")
			(hide yes)
			(effects
				(font
					(size 1.016 1.016)
					(thickness 0.1524)
				)
				(justify mirror)
			)
		)
		(duplicate_pad_numbers_are_jumpers no)
		(fp_line
			(start 0.508 -0.9398)
			(end 0.508 0.9398)
			(stroke
				(width 0.1524)
				(type default)
			)
			(layer "B.SilkS")
		)
		(fp_line
			(start -0.508 -0.9398)
			(end 0.508 -0.9398)
			(stroke
				(width 0.1524)
				(type default)
			)
			(layer "B.SilkS")
		)
		(fp_rect
			(start 0.508 0.9398)
			(end -0.508 -0.9398)
			(stroke
				(width 0)
				(type default)
			)
			(fill no)
			(layer "B.CrtYd")
		)
		(fp_rect
			(start 0.508 0.9398)
			(end -0.508 -0.9398)
			(stroke
				(width 0)
				(type default)
			)
			(fill no)
			(layer "B.Fab")
		)
		(pad "1" smd custom
			(at 0 -0.4445)
			(size 0.1397 0.1397)
			(layers "B.Cu" "B.Mask" "B.Paste")
			(net "FLA_CS_1_R")
			(options
				(clearance outline)
				(anchor circle)
			)
			(primitives
				(gr_poly
					(pts
						(arc
							(start -0.1778 0.2794)
							(mid -0.249642 0.249642)
							(end -0.2794 0.1778)
						)
						(arc
							(start -0.2794 -0.1778)
							(mid -0.249642 -0.249642)
							(end -0.1778 -0.2794)
						)
						(arc
							(start 0.1778 -0.2794)
							(mid 0.249642 -0.249642)
							(end 0.2794 -0.1778)
						)
						(arc
							(start 0.2794 0.1778)
							(mid 0.249642 0.249642)
							(end 0.1778 0.2794)
						)
					)
					(width 0)
					(fill yes)
				)
			)
		)
		(pad "2" smd custom
			(at 0 0.4445)
			(size 0.1397 0.1397)
			(layers "B.Cu" "B.Mask" "B.Paste")
			(net "FLA_CS_1")
			(options
				(clearance outline)
				(anchor circle)
			)
			(primitives
				(gr_poly
					(pts
						(arc
							(start -0.1778 0.2794)
							(mid -0.249642 0.249642)
							(end -0.2794 0.1778)
						)
						(arc
							(start -0.2794 -0.1778)
							(mid -0.249642 -0.249642)
							(end -0.1778 -0.2794)
						)
						(arc
							(start 0.1778 -0.2794)
							(mid 0.249642 -0.249642)
							(end 0.2794 -0.1778)
						)
						(arc
							(start 0.2794 0.1778)
							(mid 0.249642 0.249642)
							(end 0.1778 0.2794)
						)
					)
					(width 0)
					(fill yes)
				)
			)
		)
	)
)
